# T6G (Grand Teton) — schematic netlist excerpt (pin names and nets, part order shuffled) for the footprints in the layout excerpt that follows; sources: Cadence DE-HDL packaged netlist, KiCad conversion of 04192023_DAF0TMB3IC0_F0TG_MB_C_brd_V02_OCP.brd

C832  Q_CAP_DIFFBUS  DIFF BUS_0.22UF 6.3V 20% X6S  pkg C0201  page 65 : \1\ = P5E_CPU1_P0_TX_C_DN<2> ; \2\ = P5E_CPU1_P0_TX_DN<2>
C1554  Q_CAP  0.1UF 16V 10% X7R  pkg C0402  page 171 : A = P3V3_AUX ; B = GND
R794  Q_RES  4.7K 5% EMPTY  pkg 0201LF  page 331 : A = MODE_RT_CPU1_P1 ; B = GND

(kicad_pcb
	(version 20260206)
	(generator "pcbnew")
	(generator_version "10.0")
	(general
		(thickness 1.6)
		(legacy_teardrops no)
	)
	(paper "A4")
	(title_block
		(title "04192023_DAF0TMB3IC0_F0TG_MB_C_brd_V02_OCP.brd")
		(comment 1 "Grand Teton / footprints 4525-4527 of 8354")
	)
	(layers
		(0 "F.Cu" signal "TOP")
		(4 "In1.Cu" signal "GND")
		(6 "In2.Cu" signal "IN1")
		(8 "In3.Cu" signal "GND1")
		(10 "In4.Cu" signal "IN2")
		(12 "In5.Cu" signal "GND2")
		(14 "In6.Cu" signal "IN3")
		(16 "In7.Cu" signal "GND3")
		(18 "In8.Cu" signal "VCC")
		(20 "In9.Cu" signal "VCC1")
		(22 "In10.Cu" signal "GND4")
		(24 "In11.Cu" signal "IN4")
		(26 "In12.Cu" signal "GND5")
		(28 "In13.Cu" signal "IN5")
		(30 "In14.Cu" signal "GND6")
		(32 "In15.Cu" signal "IN6")
		(34 "In16.Cu" signal "GND7")
		(2 "B.Cu" signal "BOTTOM")
		(9 "F.Adhes" user "F.Adhesive")
		(11 "B.Adhes" user "B.Adhesive")
		(13 "F.Paste" user "Package Geometry/Pastemask Top")
		(15 "B.Paste" user "Package Geometry/Pastemask Bottom")
		(5 "F.SilkS" user "Ref Des/Silkscreen Top")
		(7 "B.SilkS" user "Ref Des/Silkscreen Bottom")
		(1 "F.Mask" user "Board Geometry/Soldermask Top")
		(3 "B.Mask" user "Board Geometry/Soldermask Bottom")
		(17 "Dwgs.User" user "User.Drawings")
		(19 "Cmts.User" user "User.Comments")
		(21 "Eco1.User" user "User.Eco1")
		(23 "Eco2.User" user "User.Eco2")
		(25 "Edge.Cuts" user "Board Geometry/Outline")
		(27 "Margin" user)
		(31 "F.CrtYd" user "Package Geometry/Place Bound Top")
		(29 "B.CrtYd" user "Package Geometry/Place Bound Bottom")
		(35 "F.Fab" user "Ref Des/Assembly Top")
		(33 "B.Fab" user "Ref Des/Assembly Bottom")
	)
	(footprint ""
		(layer "F.Cu")
		(at 116.36121 -61.602112 90)
		(property "Reference" "C1554"
			(at 0 0 90)
			(layer "F.SilkS")
			(hide yes)
			(effects
				(font
					(size 1.27 1.27)
				)
			)
		)
		(property "Value" ""
			(at 0 0 90)
			(layer "F.Fab")
			(effects
				(font
					(size 1.27 1.27)
				)
			)
		)
		(duplicate_pad_numbers_are_jumpers no)
		(fp_line
			(start 0.7874 -0.4064)
			(end 0.7874 0.4064)
			(stroke
				(width 0.1524)
				(type default)
			)
			(layer "F.SilkS")
		)
		(fp_line
			(start -0.7874 -0.4064)
			(end 0.7874 -0.4064)
			(stroke
				(width 0.1524)
				(type default)
			)
			(layer "F.SilkS")
		)
		(fp_line
			(start 0.7874 0.4064)
			(end -0.7874 0.4064)
			(stroke
				(width 0.1524)
				(type default)
			)
			(layer "F.SilkS")
		)
		(fp_line
			(start -0.7874 0.4064)
			(end -0.7874 -0.4064)
			(stroke
				(width 0.1524)
				(type default)
			)
			(layer "F.SilkS")
		)
		(fp_line
			(start -0.12065 -0.305054)
			(end -0.12065 -0.2794)
			(stroke
				(width 0.1)
				(type default)
			)
			(layer "F.Fab")
		)
		(fp_line
			(start -0.67945 -0.305054)
			(end -0.12065 -0.305054)
			(stroke
				(width 0.1)
				(type default)
			)
			(layer "F.Fab")
		)
		(fp_line
			(start 0.67945 -0.3048)
			(end 0.67945 0.3048)
			(stroke
				(width 0.1)
				(type default)
			)
			(layer "F.Fab")
		)
		(fp_line
			(start 0.12065 -0.3048)
			(end 0.67945 -0.3048)
			(stroke
				(width 0.1)
				(type default)
			)
			(layer "F.Fab")
		)
		(fp_line
			(start 0.12065 -0.2794)
			(end 0.12065 -0.3048)
			(stroke
				(width 0.1)
				(type default)
			)
			(layer "F.Fab")
		)
		(fp_line
			(start -0.12065 -0.2794)
			(end 0.12065 -0.2794)
			(stroke
				(width 0.1)
				(type default)
			)
			(layer "F.Fab")
		)
		(fp_line
			(start 0.120396 0.2794)
			(end -0.12065 0.2794)
			(stroke
				(width 0.1)
				(type default)
			)
			(layer "F.Fab")
		)
		(fp_line
			(start -0.12065 0.2794)
			(end -0.12065 0.3048)
			(stroke
				(width 0.1)
				(type default)
			)
			(layer "F.Fab")
		)
		(fp_line
			(start 0.67945 0.3048)
			(end 0.120396 0.3048)
			(stroke
				(width 0.1)
				(type default)
			)
			(layer "F.Fab")
		)
		(fp_line
			(start 0.120396 0.3048)
			(end 0.120396 0.2794)
			(stroke
				(width 0.1)
				(type default)
			)
			(layer "F.Fab")
		)
		(fp_line
			(start -0.12065 0.3048)
			(end -0.67945 0.3048)
			(stroke
				(width 0.1)
				(type default)
			)
			(layer "F.Fab")
		)
		(fp_line
			(start -0.67945 0.3048)
			(end -0.67945 -0.305054)
			(stroke
				(width 0.1)
				(type default)
			)
			(layer "F.Fab")
		)
		(pad "1" smd circle
			(at -0.40005 0 90)
			(size 0 0)
			(layers "F.Cu" "F.Mask" "F.Paste")
			(net "P3V3_AUX")
		)
		(pad "2" smd circle
			(at 0.40005 0 90)
			(size 0 0)
			(layers "F.Cu" "F.Mask" "F.Paste")
			(net "GND")
		)
	)
	(footprint ""
		(layer "F.Cu")
		(at 78.028546 -394.166852 -90)
		(property "Reference" "R794"
			(at 0 0 270)
			(layer "F.SilkS")
			(hide yes)
			(effects
				(font
					(size 1.27 1.27)
				)
			)
		)
		(property "Value" ""
			(at 0 0 270)
			(layer "F.Fab")
			(effects
				(font
					(size 1.27 1.27)
				)
			)
		)
		(duplicate_pad_numbers_are_jumpers no)
		(fp_line
			(start -0.32512 0.175006)
			(end -0.32512 -0.175006)
			(stroke
				(width 0.1)
				(type default)
			)
			(layer "F.Fab")
		)
		(fp_line
			(start 0.32512 0.175006)
			(end -0.32512 0.175006)
			(stroke
				(width 0.1)
				(type default)
			)
			(layer "F.Fab")
		)
		(fp_line
			(start -0.32512 -0.175006)
			(end 0.32512 -0.175006)
			(stroke
				(width 0.1)
				(type default)
			)
			(layer "F.Fab")
		)
		(fp_line
			(start 0.32512 -0.175006)
			(end 0.32512 0.175006)
			(stroke
				(width 0.1)
				(type default)
			)
			(layer "F.Fab")
		)
		(pad "1" smd rect
			(at -0.2667 0 270)
			(size 0.3048 0.381)
			(layers "F.Cu" "F.Mask" "F.Paste")
			(net "MODE_RT_CPU1_P1")
		)
		(pad "2" smd rect
			(at 0.2667 0 90)
			(size 0.3048 0.381)
			(layers "F.Cu" "F.Mask" "F.Paste")
			(net "GND")
		)
	)
	(footprint ""
		(layer "F.Cu")
		(at 43.904154 -373.03583 -90)
		(property "Reference" "C832"
			(at 0 0 270)
			(layer "F.SilkS")
			(hide yes)
			(effects
				(font
					(size 1.27 1.27)
				)
			)
		)
		(property "Value" ""
			(at 0 0 270)
			(layer "F.Fab")
			(effects
				(font
					(size 1.27 1.27)
				)
			)
		)
		(duplicate_pad_numbers_are_jumpers no)
		(fp_line
			(start -0.299974 0.150114)
			(end -0.299974 -0.150114)
			(stroke
				(width 0.1)
				(type default)
			)
			(layer "F.Fab")
		)
		(fp_line
			(start 0.299974 0.150114)
			(end -0.299974 0.150114)
			(stroke
				(width 0.1)
				(type default)
			)
			(layer "F.Fab")
		)
		(fp_line
			(start -0.299974 -0.150114)
			(end 0.299974 -0.150114)
			(stroke
				(width 0.1)
				(type default)
			)
			(layer "F.Fab")
		)
		(fp_line
			(start 0.299974 -0.150114)
			(end 0.299974 0.150114)
			(stroke
				(width 0.1)
				(type default)
			)
			(layer "F.Fab")
		)
		(pad "1" smd rect
			(at -0.2667 0 270)
			(size 0.3048 0.381)
			(layers "F.Cu" "F.Mask" "F.Paste")
			(net "P5E_CPU1_P0_TX_C_DN<2>")
		)
		(pad "2" smd rect
			(at 0.2667 0 270)
			(size 0.3048 0.381)
			(layers "F.Cu" "F.Mask" "F.Paste")
			(net "P5E_CPU1_P0_TX_DN<2>")
		)
	)
)
